(kicad_pcb
	(version 20241229)
	(generator "pcbnew")
	(generator_version "9.0")
	(general
		(thickness 1.294)
		(legacy_teardrops no)
	)
	(paper "A3")
	(title_block
		(title "Kintex 410T devboard")
		(date "2024-04-03")
		(rev "1.1.2")
		(comment 9 "footprints 496-501 of 975")
	)
	(layers
		(0 "F.Cu" mixed)
		(4 "In1.Cu" power)
		(6 "In2.Cu" power)
		(8 "In3.Cu" mixed)
		(10 "In4.Cu" power)
		(12 "In5.Cu" mixed)
		(14 "In6.Cu" power)
		(16 "In7.Cu" mixed)
		(18 "In8.Cu" power)
		(2 "B.Cu" mixed)
		(9 "F.Adhes" user "F.Adhesive")
		(11 "B.Adhes" user "B.Adhesive")
		(13 "F.Paste" user)
		(15 "B.Paste" user)
		(5 "F.SilkS" user "F.Silkscreen")
		(7 "B.SilkS" user "B.Silkscreen")
		(1 "F.Mask" user)
		(3 "B.Mask" user)
		(17 "Dwgs.User" user "User.Drawings")
		(19 "Cmts.User" user "User.Comments")
		(21 "Eco1.User" user "User.Eco1")
		(23 "Eco2.User" user "User.Eco2")
		(25 "Edge.Cuts" user)
		(27 "Margin" user)
		(31 "F.CrtYd" user "F.Courtyard")
		(29 "B.CrtYd" user "B.Courtyard")
		(35 "F.Fab" user)
		(33 "B.Fab" user)
	)
	(footprint "antmicro-footprints:C_0402_1005Metric"
		(layer "B.Cu")
		(at 256.101 161.6 -90)
		(descr "Capacitor SMD 0402")
		(tags "capacitor SMD 0402")
		(property "Reference" "C273"
			(at -1.35 -5.124 90)
			(layer "B.SilkS")
			(effects
				(font
					(size 0.7 0.7)
					(thickness 0.15)
				)
				(justify left bottom mirror)
			)
		)
		(property "Value" "C_10p_0402"
			(at 0 -1.4 90)
			(layer "B.Fab")
			(effects
				(font
					(size 0.7 0.7)
					(thickness 0.15)
				)
				(justify left bottom mirror)
			)
		)
		(property "Description" "SMD Multilayer Ceramic Capacitor, 10 pF, 50 V, 0402 [1005 Metric], ± 2%, C0G / NP0, GCM"
			(at 0 0 270)
			(layer "F.Fab")
			(hide yes)
			(effects
				(font
					(size 1.27 1.27)
					(thickness 0.15)
				)
			)
		)
		(property "Author" "Antmicro"
			(at 94.501 417.701 0)
			(layer "B.Fab")
			(hide yes)
			(effects
				(font
					(size 1 1)
					(thickness 0.15)
				)
				(justify mirror)
			)
		)
		(property "Dielectric" "C0G"
			(at 94.501 417.701 0)
			(layer "B.Fab")
			(hide yes)
			(effects
				(font
					(size 1 1)
					(thickness 0.15)
				)
				(justify mirror)
			)
		)
		(property "License" "Apache-2.0"
			(at 94.501 417.701 0)
			(layer "B.Fab")
			(hide yes)
			(effects
				(font
					(size 1 1)
					(thickness 0.15)
				)
				(justify mirror)
			)
		)
		(property "MPN" "GCM1555C1H100GA16D"
			(at 94.501 417.701 0)
			(layer "B.Fab")
			(hide yes)
			(effects
				(font
					(size 1 1)
					(thickness 0.15)
				)
				(justify mirror)
			)
		)
		(property "Manufacturer" "Murata"
			(at 94.501 417.701 0)
			(layer "B.Fab")
			(hide yes)
			(effects
				(font
					(size 1 1)
					(thickness 0.15)
				)
				(justify mirror)
			)
		)
		(property "Val" "10p"
			(at 94.501 417.701 0)
			(layer "B.Fab")
			(hide yes)
			(effects
				(font
					(size 1 1)
					(thickness 0.15)
				)
				(justify mirror)
			)
		)
		(property "Voltage" "50V"
			(at 94.501 417.701 0)
			(layer "B.Fab")
			(hide yes)
			(effects
				(font
					(size 1 1)
					(thickness 0.15)
				)
				(justify mirror)
			)
		)
		(sheetname "HDMI + Ethernet")
		(sheetfile "hdmi-ethernet.kicad_sch")
		(attr smd)
		(fp_rect
			(start -0.925 0.47)
			(end 0.925 -0.47)
			(stroke
				(width 0.05)
				(type default)
			)
			(fill no)
			(layer "B.CrtYd")
		)
		(fp_line
			(start -0.494 0.25)
			(end 0.504 0.25)
			(stroke
				(width 0.15)
				(type solid)
			)
			(layer "B.Fab")
		)
		(fp_line
			(start 0.504 0.25)
			(end 0.504 -0.248)
			(stroke
				(width 0.15)
				(type solid)
			)
			(layer "B.Fab")
		)
		(fp_line
			(start -0.494 -0.248)
			(end -0.494 0.25)
			(stroke
				(width 0.15)
				(type solid)
			)
			(layer "B.Fab")
		)
		(fp_line
			(start 0.504 -0.248)
			(end -0.494 -0.248)
			(stroke
				(width 0.15)
				(type solid)
			)
			(layer "B.Fab")
		)
		(pad "1" smd roundrect
			(at -0.48 0 270)
			(size 0.59 0.64)
			(layers "B.Cu" "B.Mask" "B.Paste")
			(roundrect_rratio 0.25)
			(net 1 "GND")
			(pintype "passive")
		)
		(pad "2" smd roundrect
			(at 0.48 0 270)
			(size 0.59 0.64)
			(layers "B.Cu" "B.Mask" "B.Paste")
			(roundrect_rratio 0.25)
			(net 724 "/HDMI + Ethernet/ETH1_P")
			(pintype "passive")
		)
	)
	(footprint "antmicro-footprints:R_0402_1005Metric"
		(layer "B.Cu")
		(at 186.800001 79.800001 90)
		(descr "Resistor SMD 0402")
		(tags "resistor SMD 0402")
		(property "Reference" "R143"
			(at -0.725 0.4 270)
			(layer "B.SilkS")
			(effects
				(font
					(size 0.7 0.7)
					(thickness 0.15)
				)
				(justify left bottom mirror)
			)
		)
		(property "Value" "R_100R_0402"
			(at 0 -1.4 270)
			(layer "B.Fab")
			(effects
				(font
					(size 0.7 0.7)
					(thickness 0.15)
				)
				(justify left bottom mirror)
			)
		)
		(property "Description" "SMD Chip Resistor, 100 ohm, ± 1%, 62.5 mW, 0402 [1005 Metric], Thick Film, General Purpose"
			(at 0 0 90)
			(layer "F.Fab")
			(hide yes)
			(effects
				(font
					(size 1.27 1.27)
					(thickness 0.15)
				)
			)
		)
		(property "Author" "Antmicro"
			(at 266.600002 -107 0)
			(layer "B.Fab")
			(hide yes)
			(effects
				(font
					(size 1 1)
					(thickness 0.15)
				)
				(justify mirror)
			)
		)
		(property "License" "Apache-2.0"
			(at 266.600002 -107 0)
			(layer "B.Fab")
			(hide yes)
			(effects
				(font
					(size 1 1)
					(thickness 0.15)
				)
				(justify mirror)
			)
		)
		(property "MPN" "CR0402-FX-1000GLF"
			(at 266.600002 -107 0)
			(layer "B.Fab")
			(hide yes)
			(effects
				(font
					(size 1 1)
					(thickness 0.15)
				)
				(justify mirror)
			)
		)
		(property "Manufacturer" "Bourns"
			(at 266.600002 -107 0)
			(layer "B.Fab")
			(hide yes)
			(effects
				(font
					(size 1 1)
					(thickness 0.15)
				)
				(justify mirror)
			)
		)
		(property "Tolerance" "1%"
			(at 266.600002 -107 0)
			(layer "B.Fab")
			(hide yes)
			(effects
				(font
					(size 1 1)
					(thickness 0.15)
				)
				(justify mirror)
			)
		)
		(property "Val" "100R"
			(at 266.600002 -107 0)
			(layer "B.Fab")
			(hide yes)
			(effects
				(font
					(size 1 1)
					(thickness 0.15)
				)
				(justify mirror)
			)
		)
		(sheetname "User GPIO + LED + button + DIP switch")
		(sheetfile "user-gpio.kicad_sch")
		(attr smd)
		(fp_rect
			(start -0.925 0.47)
			(end 0.925 -0.47)
			(stroke
				(width 0.05)
				(type default)
			)
			(fill no)
			(layer "B.CrtYd")
		)
		(fp_rect
			(start -0.5 0.25)
			(end 0.5 -0.25)
			(stroke
				(width 0.15)
				(type solid)
			)
			(fill no)
			(layer "B.Fab")
		)
		(pad "1" smd roundrect
			(at -0.48 0 90)
			(size 0.59 0.64)
			(layers "B.Cu" "B.Mask" "B.Paste")
			(roundrect_rratio 0.25)
			(net 488 "/FPGA Bank 12 & 13/CW_HEADER.HS2")
			(pintype "passive")
		)
		(pad "2" smd roundrect
			(at 0.48 0 90)
			(size 0.59 0.64)
			(layers "B.Cu" "B.Mask" "B.Paste")
			(roundrect_rratio 0.25)
			(net 824 "/User GPIO + LED + button + DIP switch/CW_20PIN_HS2")
			(pintype "passive")
		)
	)
	(footprint "antmicro-footprints:R_0402_1005Metric"
		(layer "B.Cu")
		(at 195.691252 91.85 180)
		(descr "Resistor SMD 0402")
		(tags "resistor SMD 0402")
		(property "Reference" "R199"
			(at 0.716252 -0.425 0)
			(layer "B.SilkS")
			(effects
				(font
					(size 0.7 0.7)
					(thickness 0.15)
				)
				(justify left bottom mirror)
			)
		)
		(property "Value" "R_10k_0402"
			(at 0 -1.4 0)
			(layer "B.Fab")
			(effects
				(font
					(size 0.7 0.7)
					(thickness 0.15)
				)
				(justify left bottom mirror)
			)
		)
		(property "Description" "SMD Chip Resistor, 10 kohm, ± 1%, 62.5 mW, 0402 [1005 Metric], Thick Film, General Purpose"
			(at 0 0 180)
			(layer "F.Fab")
			(hide yes)
			(effects
				(font
					(size 1.27 1.27)
					(thickness 0.15)
				)
			)
		)
		(property "Author" "Antmicro"
			(at 391.382504 183.7 0)
			(layer "B.Fab")
			(hide yes)
			(effects
				(font
					(size 1 1)
					(thickness 0.15)
				)
				(justify mirror)
			)
		)
		(property "License" "Apache-2.0"
			(at 391.382504 183.7 0)
			(layer "B.Fab")
			(hide yes)
			(effects
				(font
					(size 1 1)
					(thickness 0.15)
				)
				(justify mirror)
			)
		)
		(property "MPN" "CR0402-FX-1002GLF"
			(at 391.382504 183.7 0)
			(layer "B.Fab")
			(hide yes)
			(effects
				(font
					(size 1 1)
					(thickness 0.15)
				)
				(justify mirror)
			)
		)
		(property "Manufacturer" "Bourns"
			(at 391.382504 183.7 0)
			(layer "B.Fab")
			(hide yes)
			(effects
				(font
					(size 1 1)
					(thickness 0.15)
				)
				(justify mirror)
			)
		)
		(property "Tolerance" "1%"
			(at 391.382504 183.7 0)
			(layer "B.Fab")
			(hide yes)
			(effects
				(font
					(size 1 1)
					(thickness 0.15)
				)
				(justify mirror)
			)
		)
		(property "Val" "10k"
			(at 391.382504 183.7 0)
			(layer "B.Fab")
			(hide yes)
			(effects
				(font
					(size 1 1)
					(thickness 0.15)
				)
				(justify mirror)
			)
		)
		(sheetname "HDMI + Ethernet")
		(sheetfile "hdmi-ethernet.kicad_sch")
		(attr smd)
		(fp_rect
			(start -0.925 0.47)
			(end 0.925 -0.47)
			(stroke
				(width 0.05)
				(type default)
			)
			(fill no)
			(layer "B.CrtYd")
		)
		(fp_rect
			(start -0.5 0.25)
			(end 0.5 -0.25)
			(stroke
				(width 0.15)
				(type solid)
			)
			(fill no)
			(layer "B.Fab")
		)
		(pad "1" smd roundrect
			(at -0.48 0 180)
			(size 0.59 0.64)
			(layers "B.Cu" "B.Mask" "B.Paste")
			(roundrect_rratio 0.25)
			(net 503 "/FPGA Bank 16 & 17/GBE_RGMII.RXD3")
			(pintype "passive")
		)
		(pad "2" smd roundrect
			(at 0.48 0 180)
			(size 0.59 0.64)
			(layers "B.Cu" "B.Mask" "B.Paste")
			(roundrect_rratio 0.25)
			(net 24 "+3V3")
			(pintype "passive")
		)
	)
	(footprint "antmicro-footprints:C_0603_1608Metric"
		(layer "B.Cu")
		(at 200 131.325 -90)
		(descr "Capacitor SMD 0603")
		(tags "capacitor 0603")
		(property "Reference" "C384"
			(at -30.7 -25.75 90)
			(layer "B.SilkS")
			(effects
				(font
					(size 0.7 0.7)
					(thickness 0.15)
				)
				(justify left bottom mirror)
			)
		)
		(property "Value" "C_47u_0603"
			(at 0 -1.6 90)
			(layer "B.Fab")
			(effects
				(font
					(size 0.7 0.7)
					(thickness 0.15)
				)
				(justify left bottom mirror)
			)
		)
		(property "Description" "SMD Multilayer Ceramic Capacitor, 47 µF, 6.3 V, 0603 [1608 Metric], ± 20%, X5R, GRM Series"
			(at 0 0 270)
			(layer "F.Fab")
			(hide yes)
			(effects
				(font
					(size 1.27 1.27)
					(thickness 0.15)
				)
			)
		)
		(property "Author" "Antmicro"
			(at 68.675 331.325 0)
			(layer "B.Fab")
			(hide yes)
			(effects
				(font
					(size 1 1)
					(thickness 0.15)
				)
				(justify mirror)
			)
		)
		(property "Dielectric" ""
			(at 68.675 331.325 0)
			(layer "B.Fab")
			(hide yes)
			(effects
				(font
					(size 1 1)
					(thickness 0.15)
				)
				(justify mirror)
			)
		)
		(property "License" "Apache-2.0"
			(at 68.675 331.325 0)
			(layer "B.Fab")
			(hide yes)
			(effects
				(font
					(size 1 1)
					(thickness 0.15)
				)
				(justify mirror)
			)
		)
		(property "MPN" "GRM188R60J476ME15D"
			(at 68.675 331.325 0)
			(layer "B.Fab")
			(hide yes)
			(effects
				(font
					(size 1 1)
					(thickness 0.15)
				)
				(justify mirror)
			)
		)
		(property "Manufacturer" "Murata"
			(at 68.675 331.325 0)
			(layer "B.Fab")
			(hide yes)
			(effects
				(font
					(size 1 1)
					(thickness 0.15)
				)
				(justify mirror)
			)
		)
		(property "Val" "47u"
			(at 68.675 331.325 0)
			(layer "B.Fab")
			(hide yes)
			(effects
				(font
					(size 1 1)
					(thickness 0.15)
				)
				(justify mirror)
			)
		)
		(property "Voltage" ""
			(at 68.675 331.325 0)
			(layer "B.Fab")
			(hide yes)
			(effects
				(font
					(size 1 1)
					(thickness 0.15)
				)
				(justify mirror)
			)
		)
		(sheetname "FPGA supply")
		(sheetfile "fpga-supply.kicad_sch")
		(attr smd)
		(fp_line
			(start -0.15 0.4)
			(end 0.15 0.4)
			(stroke
				(width 0.15)
				(type solid)
			)
			(layer "B.SilkS")
		)
		(fp_line
			(start -0.15 -0.4)
			(end 0.15 -0.4)
			(stroke
				(width 0.15)
				(type solid)
			)
			(layer "B.SilkS")
		)
		(fp_rect
			(start -1.25 0.65)
			(end 1.25 -0.65)
			(stroke
				(width 0.05)
				(type solid)
			)
			(fill no)
			(layer "B.CrtYd")
		)
		(fp_rect
			(start -0.8 0.4)
			(end 0.8 -0.4)
			(stroke
				(width 0.15)
				(type solid)
			)
			(fill no)
			(layer "B.Fab")
		)
		(pad "1" smd roundrect
			(at -0.7 0 270)
			(size 0.8 1)
			(layers "B.Cu" "B.Mask" "B.Paste")
			(roundrect_rratio 0.2)
			(net 1 "GND")
			(pintype "passive")
		)
		(pad "2" smd roundrect
			(at 0.7 0 270)
			(size 0.8 1)
			(layers "B.Cu" "B.Mask" "B.Paste")
			(roundrect_rratio 0.2)
			(net 650 "+1V0")
			(pintype "passive")
		)
	)
	(footprint "antmicro-footprints:C_0201"
		(layer "B.Cu")
		(at 203.45 131.6 -90)
		(descr "Capacitor SMD 0201")
		(tags "capacitor SMD 0201")
		(property "Reference" "C22"
			(at -29.575 -28.2 90)
			(layer "B.SilkS")
			(effects
				(font
					(size 0.7 0.7)
					(thickness 0.15)
				)
				(justify left bottom mirror)
			)
		)
		(property "Value" "C_4u7_0201"
			(at 0 -1.4 90)
			(layer "B.Fab")
			(effects
				(font
					(size 0.7 0.7)
					(thickness 0.15)
				)
				(justify left bottom mirror)
			)
		)
		(property "Description" "SMD Multilayer Ceramic Capacitor, 4.7 µF, 6.3 V, 0201 [0603 Metric], ± 20%, X5R, GRM Series"
			(at 0 0 270)
			(layer "F.Fab")
			(hide yes)
			(effects
				(font
					(size 1.27 1.27)
					(thickness 0.15)
				)
			)
		)
		(property "Author" "Antmicro"
			(at 71.85 335.05 0)
			(layer "B.Fab")
			(hide yes)
			(effects
				(font
					(size 1 1)
					(thickness 0.15)
				)
				(justify mirror)
			)
		)
		(property "Dielectric" ""
			(at 71.85 335.05 0)
			(layer "B.Fab")
			(hide yes)
			(effects
				(font
					(size 1 1)
					(thickness 0.15)
				)
				(justify mirror)
			)
		)
		(property "License" "Apache-2.0"
			(at 71.85 335.05 0)
			(layer "B.Fab")
			(hide yes)
			(effects
				(font
					(size 1 1)
					(thickness 0.15)
				)
				(justify mirror)
			)
		)
		(property "MPN" "GRM035R60J475ME15D"
			(at 71.85 335.05 0)
			(layer "B.Fab")
			(hide yes)
			(effects
				(font
					(size 1 1)
					(thickness 0.15)
				)
				(justify mirror)
			)
		)
		(property "Manufacturer" "Murata"
			(at 71.85 335.05 0)
			(layer "B.Fab")
			(hide yes)
			(effects
				(font
					(size 1 1)
					(thickness 0.15)
				)
				(justify mirror)
			)
		)
		(property "Val" "4u7"
			(at 71.85 335.05 0)
			(layer "B.Fab")
			(hide yes)
			(effects
				(font
					(size 1 1)
					(thickness 0.15)
				)
				(justify mirror)
			)
		)
		(property "Voltage" ""
			(at 71.85 335.05 0)
			(layer "B.Fab")
			(hide yes)
			(effects
				(font
					(size 1 1)
					(thickness 0.15)
				)
				(justify mirror)
			)
		)
		(sheetname "FPGA supply")
		(sheetfile "fpga-supply.kicad_sch")
		(attr smd)
		(fp_rect
			(start -0.7 0.35)
			(end 0.7 -0.35)
			(stroke
				(width 0.05)
				(type default)
			)
			(fill no)
			(layer "B.CrtYd")
		)
		(fp_rect
			(start 0.3 -0.15)
			(end -0.301 0.149)
			(stroke
				(width 0.15)
				(type solid)
			)
			(fill no)
			(layer "B.Fab")
		)
		(pad "" smd roundrect
			(at -0.349 0.002 270)
			(size 0.318 0.36)
			(layers "B.Paste")
			(roundrect_rratio 0.25)
		)
		(pad "" smd roundrect
			(at 0.341 0.002 270)
			(size 0.318 0.36)
			(layers "B.Paste")
			(roundrect_rratio 0.25)
		)
		(pad "1" smd roundrect
			(at -0.321 0.002 270)
			(size 0.46 0.4)
			(layers "B.Cu" "B.Mask")
			(roundrect_rratio 0.25)
			(net 1 "GND")
			(pintype "passive")
		)
		(pad "2" smd roundrect
			(at 0.32 0.002 270)
			(size 0.46 0.4)
			(layers "B.Cu" "B.Mask")
			(roundrect_rratio 0.25)
			(net 650 "+1V0")
			(pintype "passive")
		)
	)
	(footprint "antmicro-footprints:R_0402_1005Metric"
		(layer "B.Cu")
		(at 258.4 83.8 -90)
		(descr "Resistor SMD 0402")
		(tags "resistor SMD 0402")
		(property "Reference" "R353"
			(at -1.375 -1.25 90)
			(layer "B.SilkS")
			(effects
				(font
					(size 0.7 0.7)
					(thickness 0.15)
				)
				(justify left bottom mirror)
			)
		)
		(property "Value" "R_100k_0402"
			(at 0 -1.4 90)
			(layer "B.Fab")
			(effects
				(font
					(size 0.7 0.7)
					(thickness 0.15)
				)
				(justify left bottom mirror)
			)
		)
		(property "Description" "SMD Chip Resistor, 100 kohm, ± 1%, 62.5 mW, 0402 [1005 Metric], Thick Film, General Purpose"
			(at 0 0 270)
			(layer "F.Fab")
			(hide yes)
			(effects
				(font
					(size 1.27 1.27)
					(thickness 0.15)
				)
			)
		)
		(property "Author" "Antmicro"
			(at 174.6 342.2 0)
			(layer "B.Fab")
			(hide yes)
			(effects
				(font
					(size 1 1)
					(thickness 0.15)
				)
				(justify mirror)
			)
		)
		(property "License" "Apache-2.0"
			(at 174.6 342.2 0)
			(layer "B.Fab")
			(hide yes)
			(effects
				(font
					(size 1 1)
					(thickness 0.15)
				)
				(justify mirror)
			)
		)
		(property "MPN" "CR0402-FX-1003GLF"
			(at 174.6 342.2 0)
			(layer "B.Fab")
			(hide yes)
			(effects
				(font
					(size 1 1)
					(thickness 0.15)
				)
				(justify mirror)
			)
		)
		(property "Manufacturer" "Bourns"
			(at 174.6 342.2 0)
			(layer "B.Fab")
			(hide yes)
			(effects
				(font
					(size 1 1)
					(thickness 0.15)
				)
				(justify mirror)
			)
		)
		(property "Tolerance" "1%"
			(at 174.6 342.2 0)
			(layer "B.Fab")
			(hide yes)
			(effects
				(font
					(size 1 1)
					(thickness 0.15)
				)
				(justify mirror)
			)
		)
		(property "Val" "100k"
			(at 174.6 342.2 0)
			(layer "B.Fab")
			(hide yes)
			(effects
				(font
					(size 1 1)
					(thickness 0.15)
				)
				(justify mirror)
			)
		)
		(sheetname "User GPIO + LED + button + DIP switch")
		(sheetfile "user-gpio.kicad_sch")
		(attr smd)
		(fp_rect
			(start -0.925 0.47)
			(end 0.925 -0.47)
			(stroke
				(width 0.05)
				(type default)
			)
			(fill no)
			(layer "B.CrtYd")
		)
		(fp_rect
			(start -0.5 0.25)
			(end 0.5 -0.25)
			(stroke
				(width 0.15)
				(type solid)
			)
			(fill no)
			(layer "B.Fab")
		)
		(pad "1" smd roundrect
			(at -0.48 0 270)
			(size 0.59 0.64)
			(layers "B.Cu" "B.Mask" "B.Paste")
			(roundrect_rratio 0.25)
			(net 1299 "/USER_IO.LED_GREEN0")
			(pintype "passive")
		)
		(pad "2" smd roundrect
			(at 0.48 0 270)
			(size 0.59 0.64)
			(layers "B.Cu" "B.Mask" "B.Paste")
			(roundrect_rratio 0.25)
			(net 1 "GND")
			(pintype "passive")
		)
	)
)
